# T6G (Grand Teton) — schematic netlist excerpt (pin names and nets, part order shuffled) for the footprints in the layout excerpt that follows; sources: Cadence DE-HDL packaged netlist, KiCad conversion of 04192023_DAF0TMB3IC0_F0TG_MB_C_brd_V02_OCP.brd

C524  Q_CAP  0.1UF 10V 10% X7S  pkg C0201  page 279 : A = P0V9_CPU0_RT_2D ; B = GND
R399  Q_RES  1K 1% CHIP  pkg 0402LF  page 27 : A = PVDD18_S5_P0 ; B = JTAG_CPU0_TDI
PC446_2  Q_CAP  22UF 16V 20% X6S  pkg C0805  page 222 : A = SW_P12V_AUX_PVDDIO_P1_FLT ; B = GND

(kicad_pcb
	(version 20260206)
	(generator "pcbnew")
	(generator_version "10.0")
	(general
		(thickness 1.6)
		(legacy_teardrops no)
	)
	(paper "A4")
	(title_block
		(title "04192023_DAF0TMB3IC0_F0TG_MB_C_brd_V02_OCP.brd")
		(comment 1 "Grand Teton / footprints 6217-6219 of 8354")
	)
	(layers
		(0 "F.Cu" signal "TOP")
		(4 "In1.Cu" signal "GND")
		(6 "In2.Cu" signal "IN1")
		(8 "In3.Cu" signal "GND1")
		(10 "In4.Cu" signal "IN2")
		(12 "In5.Cu" signal "GND2")
		(14 "In6.Cu" signal "IN3")
		(16 "In7.Cu" signal "GND3")
		(18 "In8.Cu" signal "VCC")
		(20 "In9.Cu" signal "VCC1")
		(22 "In10.Cu" signal "GND4")
		(24 "In11.Cu" signal "IN4")
		(26 "In12.Cu" signal "GND5")
		(28 "In13.Cu" signal "IN5")
		(30 "In14.Cu" signal "GND6")
		(32 "In15.Cu" signal "IN6")
		(34 "In16.Cu" signal "GND7")
		(2 "B.Cu" signal "BOTTOM")
		(9 "F.Adhes" user "F.Adhesive")
		(11 "B.Adhes" user "B.Adhesive")
		(13 "F.Paste" user "Package Geometry/Pastemask Top")
		(15 "B.Paste" user "Package Geometry/Pastemask Bottom")
		(5 "F.SilkS" user "Ref Des/Silkscreen Top")
		(7 "B.SilkS" user "Ref Des/Silkscreen Bottom")
		(1 "F.Mask" user "Board Geometry/Soldermask Top")
		(3 "B.Mask" user "Board Geometry/Soldermask Bottom")
		(17 "Dwgs.User" user "User.Drawings")
		(19 "Cmts.User" user "User.Comments")
		(21 "Eco1.User" user "User.Eco1")
		(23 "Eco2.User" user "User.Eco2")
		(25 "Edge.Cuts" user "Board Geometry/Outline")
		(27 "Margin" user)
		(31 "F.CrtYd" user "Package Geometry/Place Bound Top")
		(29 "B.CrtYd" user "Package Geometry/Place Bound Bottom")
		(35 "F.Fab" user "Ref Des/Assembly Top")
		(33 "B.Fab" user "Ref Des/Assembly Bottom")
	)
	(footprint ""
		(layer "B.Cu")
		(at 381.552958 -208.530952 -90)
		(property "Reference" "R399"
			(at 0 0 90)
			(layer "B.SilkS")
			(hide yes)
			(effects
				(font
					(size 1.27 1.27)
				)
				(justify mirror)
			)
		)
		(property "Value" ""
			(at 0 0 90)
			(layer "B.Fab")
			(effects
				(font
					(size 1.27 1.27)
				)
				(justify mirror)
			)
		)
		(duplicate_pad_numbers_are_jumpers no)
		(fp_line
			(start -0.7874 0.4064)
			(end 0.7874 0.4064)
			(stroke
				(width 0.1524)
				(type default)
			)
			(layer "B.SilkS")
		)
		(fp_line
			(start 0.7874 0.4064)
			(end 0.7874 -0.4064)
			(stroke
				(width 0.1524)
				(type default)
			)
			(layer "B.SilkS")
		)
		(fp_line
			(start -0.7874 -0.4064)
			(end -0.7874 0.4064)
			(stroke
				(width 0.1524)
				(type default)
			)
			(layer "B.SilkS")
		)
		(fp_line
			(start 0.7874 -0.4064)
			(end -0.7874 -0.4064)
			(stroke
				(width 0.1524)
				(type default)
			)
			(layer "B.SilkS")
		)
		(fp_line
			(start -0.67945 0.3048)
			(end -0.120396 0.3048)
			(stroke
				(width 0.1)
				(type default)
			)
			(layer "B.Fab")
		)
		(fp_line
			(start -0.120396 0.3048)
			(end -0.120396 0.2794)
			(stroke
				(width 0.1)
				(type default)
			)
			(layer "B.Fab")
		)
		(fp_line
			(start 0.12065 0.3048)
			(end 0.67945 0.3048)
			(stroke
				(width 0.1)
				(type default)
			)
			(layer "B.Fab")
		)
		(fp_line
			(start 0.67945 0.3048)
			(end 0.67945 -0.305054)
			(stroke
				(width 0.1)
				(type default)
			)
			(layer "B.Fab")
		)
		(fp_line
			(start -0.120396 0.2794)
			(end 0.12065 0.2794)
			(stroke
				(width 0.1)
				(type default)
			)
			(layer "B.Fab")
		)
		(fp_line
			(start 0.12065 0.2794)
			(end 0.12065 0.3048)
			(stroke
				(width 0.1)
				(type default)
			)
			(layer "B.Fab")
		)
		(fp_line
			(start -0.12065 -0.2794)
			(end -0.12065 -0.3048)
			(stroke
				(width 0.1)
				(type default)
			)
			(layer "B.Fab")
		)
		(fp_line
			(start 0.12065 -0.2794)
			(end -0.12065 -0.2794)
			(stroke
				(width 0.1)
				(type default)
			)
			(layer "B.Fab")
		)
		(fp_line
			(start -0.67945 -0.3048)
			(end -0.67945 0.3048)
			(stroke
				(width 0.1)
				(type default)
			)
			(layer "B.Fab")
		)
		(fp_line
			(start -0.12065 -0.3048)
			(end -0.67945 -0.3048)
			(stroke
				(width 0.1)
				(type default)
			)
			(layer "B.Fab")
		)
		(fp_line
			(start 0.12065 -0.305054)
			(end 0.12065 -0.2794)
			(stroke
				(width 0.1)
				(type default)
			)
			(layer "B.Fab")
		)
		(fp_line
			(start 0.67945 -0.305054)
			(end 0.12065 -0.305054)
			(stroke
				(width 0.1)
				(type default)
			)
			(layer "B.Fab")
		)
		(pad "1" smd circle
			(at 0.40005 0 90)
			(size 0 0)
			(layers "B.Cu" "B.Mask" "B.Paste")
			(net "PVDD18_S5_P0")
		)
		(pad "2" smd circle
			(at -0.40005 0 90)
			(size 0 0)
			(layers "B.Cu" "B.Mask" "B.Paste")
			(net "JTAG_CPU0_TDI")
		)
	)
	(footprint ""
		(layer "B.Cu")
		(at 46.308518 -350.660716 -90)
		(property "Reference" "PC446_2"
			(at 0 0 90)
			(layer "B.SilkS")
			(hide yes)
			(effects
				(font
					(size 1.27 1.27)
				)
				(justify mirror)
			)
		)
		(property "Value" ""
			(at 0 0 90)
			(layer "B.Fab")
			(effects
				(font
					(size 1.27 1.27)
				)
				(justify mirror)
			)
		)
		(duplicate_pad_numbers_are_jumpers no)
		(fp_line
			(start -1.524 0.762)
			(end 1.524 0.762)
			(stroke
				(width 0.1524)
				(type default)
			)
			(layer "B.SilkS")
		)
		(fp_line
			(start 1.524 0.762)
			(end 1.524 -0.762)
			(stroke
				(width 0.1524)
				(type default)
			)
			(layer "B.SilkS")
		)
		(fp_line
			(start -1.524 -0.762)
			(end -1.524 0.762)
			(stroke
				(width 0.1524)
				(type default)
			)
			(layer "B.SilkS")
		)
		(fp_line
			(start 1.524 -0.762)
			(end -1.524 -0.762)
			(stroke
				(width 0.1524)
				(type default)
			)
			(layer "B.SilkS")
		)
		(fp_line
			(start -1.1049 0.724916)
			(end -1.1049 -0.724916)
			(stroke
				(width 0.1)
				(type default)
			)
			(layer "B.Fab")
		)
		(fp_line
			(start 1.1049 0.724916)
			(end -1.1049 0.724916)
			(stroke
				(width 0.1)
				(type default)
			)
			(layer "B.Fab")
		)
		(fp_line
			(start -1.1049 -0.724916)
			(end 1.1049 -0.724916)
			(stroke
				(width 0.1)
				(type default)
			)
			(layer "B.Fab")
		)
		(fp_line
			(start 1.1049 -0.724916)
			(end 1.1049 0.724916)
			(stroke
				(width 0.1)
				(type default)
			)
			(layer "B.Fab")
		)
		(pad "1" smd rect
			(at 0.889 0 270)
			(size 1.016 1.27)
			(layers "B.Cu" "B.Mask" "B.Paste")
			(net "SW_P12V_AUX_PVDDIO_P1_FLT")
		)
		(pad "2" smd rect
			(at -0.889 0 270)
			(size 1.016 1.27)
			(layers "B.Cu" "B.Mask" "B.Paste")
			(net "GND")
		)
	)
	(footprint ""
		(layer "B.Cu")
		(at 315.518292 -396.393162 -90)
		(property "Reference" "C524"
			(at 0 0 90)
			(layer "B.SilkS")
			(hide yes)
			(effects
				(font
					(size 1.27 1.27)
				)
				(justify mirror)
			)
		)
		(property "Value" ""
			(at 0 0 90)
			(layer "B.Fab")
			(effects
				(font
					(size 1.27 1.27)
				)
				(justify mirror)
			)
		)
		(duplicate_pad_numbers_are_jumpers no)
		(fp_line
			(start -0.299974 0.150114)
			(end 0.299974 0.150114)
			(stroke
				(width 0.1)
				(type default)
			)
			(layer "B.Fab")
		)
		(fp_line
			(start 0.299974 0.150114)
			(end 0.299974 -0.150114)
			(stroke
				(width 0.1)
				(type default)
			)
			(layer "B.Fab")
		)
		(fp_line
			(start -0.299974 -0.150114)
			(end -0.299974 0.150114)
			(stroke
				(width 0.1)
				(type default)
			)
			(layer "B.Fab")
		)
		(fp_line
			(start 0.299974 -0.150114)
			(end -0.299974 -0.150114)
			(stroke
				(width 0.1)
				(type default)
			)
			(layer "B.Fab")
		)
		(pad "1" smd rect
			(at 0.2667 0 90)
			(size 0.3048 0.381)
			(layers "B.Cu" "B.Mask" "B.Paste")
			(net "P0V9_CPU0_RT_2D")
		)
		(pad "2" smd rect
			(at -0.2667 0 90)
			(size 0.3048 0.381)
			(layers "B.Cu" "B.Mask" "B.Paste")
			(net "GND")
		)
	)
)
